FILE_TYPE = CONNECTIVITY;
{Allegro Design Entry HDL 17.2-2016 S081 (4005846) 1/11/2022}
"PAGE_NUMBER" = 53;
0"NC";
1"WAFL_CPU0_TX0_CPU1_RX1_DP";
2"WAFL_CPU0_TX0_CPU1_RX1_DN"$PHYS_NET_NAME"P3E_M2_0_SATA_RX_DP";
3"WAFL_CPU1_TX1_CPU0_RX0_DN"$PHYS_NET_NAME"P3E_M2_0_SATA_RX_DP";
4"WAFL_CPU1_TX1_CPU0_RX0_DP";
%"GENOA_SP5"
"19","(-4450,4775)","0","pure_quanta","I56";
;
LOCATION"U26"
$SEC"19"
CDS_SEC"19"
MATERIAL"IO"
VALUE"SOCKET6096_13568-001"
PART_NUMBER"DGA^6000030"
PART_TYPE"SMLF"
CDS_LIB"pure_quanta"
CDS_LMAN_SYM_OUTLINE"-800,600,800,-600"
NEEDS_NO_SIZE"TRUE";
"WAFL_TXP1||P5_TXP1"
$PN"C47"4;
"WAFL_TXN1||P5_TXN1"
$PN"C48"3;
"WAFL_TXP0||P5_TXP0"
$PN"C50"0;
"WAFL_TXN0||P5_TXN0"
$PN"C51"0;
"WAFL_RXP1||P5_RXP1"
$PN"E46"1;
"WAFL_RXN1||P5_RXN1"
$PN"E47"2;
"WAFL_RXP0||P5_RXP0"
$PN"E49"0;
"WAFL_RXN0||P5_RXN0"
$PN"E50"0;
"P4_RXN1"
$PN"DG50"0;
"P4_RXN0"
$PN"DG53"0;
"P4_RXP1"
$PN"DG51"0;
"P4_TXN1"
$PN"DE49"0;
"P4_RXP0"
$PN"DG54"0;
"P4_TXN0"
$PN"DE52"0;
"P4_TXP1"
$PN"DE50"0;
"P4_TXP0"
$PN"DE53"0;
"P5_TXP3"
$PN"C41"0;
"P5_TXP2"
$PN"C44"0;
"P5_TXN3"
$PN"C42"0;
"P5_TXN2"
$PN"C45"0;
"P5_RXP3"
$PN"E40"0;
"P5_RXP2"
$PN"E43"0;
"P5_RXN3"
$PN"E41"0;
"P5_RXN2"
$PN"E44"0;
"P4_TXP3"
$PN"DE44"0;
"P4_TXP2"
$PN"DE47"0;
"P4_TXN3"
$PN"DE43"0;
"P4_TXN2"
$PN"DE46"0;
"P4_RXP3"
$PN"DG45"0;
"P4_RXP2"
$PN"DG48"0;
"P4_RXN3"
$PN"DG44"0;
"P4_RXN2"
$PN"DG47"0;
END.
